(kicad_pcb
	(version 20260206)
	(generator "pcbnew")
	(generator_version "10.0")
	(general
		(thickness 1.6)
		(legacy_teardrops no)
	)
	(paper "A4")
	(title_block
		(title "Wiwynn_Tioga_Pass_MB.brd")
		(comment 1 "Tioga Pass / footprints 1345-1351 of 4770")
	)
	(layers
		(0 "F.Cu" signal "TOP")
		(4 "In1.Cu" signal "L2GND")
		(6 "In2.Cu" signal "L3")
		(8 "In3.Cu" signal "L4GND")
		(10 "In4.Cu" signal "L5")
		(12 "In5.Cu" signal "L6GND")
		(14 "In6.Cu" signal "L7VCC")
		(16 "In7.Cu" signal "L8VCC")
		(18 "In8.Cu" signal "L9GND")
		(20 "In9.Cu" signal "L10")
		(22 "In10.Cu" signal "L11GND")
		(24 "In11.Cu" signal "L12")
		(26 "In12.Cu" signal "L13GND")
		(2 "B.Cu" signal "BOTTOM")
		(9 "F.Adhes" user "F.Adhesive")
		(11 "B.Adhes" user "B.Adhesive")
		(13 "F.Paste" user "Package Geometry/Pastemask Top")
		(15 "B.Paste" user "Package Geometry/Pastemask Bottom")
		(5 "F.SilkS" user "Ref Des/Silkscreen Top")
		(7 "B.SilkS" user "Ref Des/Silkscreen Bottom")
		(1 "F.Mask" user "Board Geometry/Soldermask Top")
		(3 "B.Mask" user "Board Geometry/Soldermask Bottom")
		(17 "Dwgs.User" user "User.Drawings")
		(19 "Cmts.User" user "User.Comments")
		(21 "Eco1.User" user "User.Eco1")
		(23 "Eco2.User" user "User.Eco2")
		(25 "Edge.Cuts" user "Board Geometry/Outline")
		(27 "Margin" user)
		(31 "F.CrtYd" user "Package Geometry/Place Bound Top")
		(29 "B.CrtYd" user "Package Geometry/Place Bound Bottom")
		(35 "F.Fab" user "Ref Des/Assembly Top")
		(33 "B.Fab" user "Ref Des/Assembly Bottom")
	)
	(footprint ""
		(layer "F.Cu")
		(at 344.932 -93.5228 90)
		(property "Reference" "RT48"
			(at 0 0 90)
			(layer "F.SilkS")
			(hide yes)
			(effects
				(font
					(size 1.27 1.27)
				)
			)
		)
		(property "Value" "*"
			(at -0.0254 -2.6289 90)
			(unlocked yes)
			(layer "F.Fab")
			(hide yes)
			(effects
				(font
					(size 1.27 1.016)
					(thickness 0.1524)
				)
			)
		)
		(property "Device Type" "1R3F-GP_RCL_GP-1R3F-GP,64.1R00A"
			(at -0.0254 -4.1529 90)
			(unlocked yes)
			(layer "F.Fab")
			(hide yes)
			(effects
				(font
					(size 1.27 1.016)
					(thickness 0.1524)
				)
			)
		)
		(duplicate_pad_numbers_are_jumpers no)
		(fp_line
			(start 0.2032 0)
			(end 0.4826 0)
			(stroke
				(width 0.2032)
				(type default)
			)
			(layer "F.SilkS")
		)
		(fp_line
			(start -0.4826 0)
			(end -0.2032 0)
			(stroke
				(width 0.2032)
				(type default)
			)
			(layer "F.SilkS")
		)
		(fp_rect
			(start -0.5842 1.3335)
			(end 0.5842 -1.3335)
			(stroke
				(width 0)
				(type default)
			)
			(fill no)
			(layer "F.CrtYd")
		)
		(fp_rect
			(start -0.5842 1.3335)
			(end 0.5842 -1.3335)
			(stroke
				(width 0)
				(type default)
			)
			(fill no)
			(layer "F.Fab")
		)
		(pad "1" smd custom
			(at 0 -0.762 90)
			(size 0.2159 0.2159)
			(layers "F.Cu" "F.Mask" "F.Paste")
			(net "VR_PVCCIO_CPU0_PH1_SW_RC")
			(options
				(clearance outline)
				(anchor circle)
			)
			(primitives
				(gr_poly
					(pts
						(arc
							(start -0.3302 -0.4318)
							(mid -0.402042 -0.402042)
							(end -0.4318 -0.3302)
						)
						(arc
							(start -0.4318 0.3302)
							(mid -0.402042 0.402042)
							(end -0.3302 0.4318)
						)
						(arc
							(start 0.3302 0.4318)
							(mid 0.402042 0.402042)
							(end 0.4318 0.3302)
						)
						(arc
							(start 0.4318 -0.3302)
							(mid 0.402042 -0.402042)
							(end 0.3302 -0.4318)
						)
					)
					(width 0)
					(fill yes)
				)
			)
		)
		(pad "2" smd custom
			(at 0 0.762 90)
			(size 0.2159 0.2159)
			(layers "F.Cu" "F.Mask" "F.Paste")
			(net "GND")
			(options
				(clearance outline)
				(anchor circle)
			)
			(primitives
				(gr_poly
					(pts
						(arc
							(start -0.3302 -0.4318)
							(mid -0.402042 -0.402042)
							(end -0.4318 -0.3302)
						)
						(arc
							(start -0.4318 0.3302)
							(mid -0.402042 0.402042)
							(end -0.3302 0.4318)
						)
						(arc
							(start 0.3302 0.4318)
							(mid 0.402042 0.402042)
							(end 0.4318 0.3302)
						)
						(arc
							(start 0.4318 -0.3302)
							(mid 0.402042 -0.402042)
							(end 0.3302 -0.4318)
						)
					)
					(width 0)
					(fill yes)
				)
			)
		)
	)
	(footprint ""
		(layer "F.Cu")
		(at 245.7323 -140.208 -90)
		(property "Reference" "C5A11"
			(at 1.848866 0.752348 270)
			(unlocked yes)
			(layer "F.SilkS")
			(effects
				(font
					(size 1.27 0.9652)
					(thickness 0.1524)
				)
			)
		)
		(property "Value" ""
			(at 0 0 270)
			(layer "F.Fab")
			(effects
				(font
					(size 1.27 1.27)
				)
			)
		)
		(duplicate_pad_numbers_are_jumpers no)
		(fp_rect
			(start -0.500126 1.598422)
			(end 0.500126 -0.201422)
			(stroke
				(width 0)
				(type default)
			)
			(fill no)
			(layer "F.CrtYd")
		)
		(fp_line
			(start -0.500126 1.598422)
			(end -0.500126 -0.201422)
			(stroke
				(width 0.1)
				(type default)
			)
			(layer "F.Fab")
		)
		(fp_line
			(start 0.500126 1.598422)
			(end -0.500126 1.598422)
			(stroke
				(width 0.1)
				(type default)
			)
			(layer "F.Fab")
		)
		(fp_line
			(start -0.500126 -0.201422)
			(end 0.500126 -0.201422)
			(stroke
				(width 0.1)
				(type default)
			)
			(layer "F.Fab")
		)
		(fp_line
			(start 0.500126 -0.201422)
			(end 0.500126 1.598422)
			(stroke
				(width 0.1)
				(type default)
			)
			(layer "F.Fab")
		)
		(pad "1" smd rect
			(at 0 0 180)
			(size 0.889 0.9906)
			(layers "F.Cu" "F.Mask" "F.Paste")
			(net "PVDDQ_DEF")
		)
		(pad "2" smd rect
			(at 0 1.397 180)
			(size 0.889 0.9906)
			(layers "F.Cu" "F.Mask" "F.Paste")
			(net "GND")
		)
		(zone
			(layer "F.Cu")
			(hatch none 0.5)
			(connect_pads
				(clearance 0)
			)
			(min_thickness 0.25)
			(keepout
				(tracks not_allowed)
				(vias allowed)
				(pads allowed)
				(copperpour not_allowed)
				(footprints allowed)
			)
			(placement
				(enabled no)
				(sheetname "")
			)
			(fill
				(thermal_gap 0.5)
				(thermal_bridge_width 0.5)
				(island_removal_mode 0)
			)
			(polygon
				(pts
					(xy 244.7798 -140.7033) (xy 244.7798 -139.7127) (xy 245.2878 -139.7127) (xy 245.2878 -140.7033)
				)
			)
		)
		(zone
			(layer "F.Cu")
			(hatch none 0.5)
			(connect_pads
				(clearance 0)
			)
			(min_thickness 0.25)
			(keepout
				(tracks allowed)
				(vias not_allowed)
				(pads allowed)
				(copperpour not_allowed)
				(footprints allowed)
			)
			(placement
				(enabled no)
				(sheetname "")
			)
			(fill
				(thermal_gap 0.5)
				(thermal_bridge_width 0.5)
				(island_removal_mode 0)
			)
			(polygon
				(pts
					(xy 244.7798 -140.7033) (xy 244.7798 -139.7127) (xy 245.2878 -139.7127) (xy 245.2878 -140.7033)
				)
			)
		)
	)
	(footprint ""
		(layer "F.Cu")
		(at 164.084 -69.9262 90)
		(property "Reference" "R4D49"
			(at 0 0 90)
			(layer "F.SilkS")
			(hide yes)
			(effects
				(font
					(size 1.27 1.27)
				)
			)
		)
		(property "Value" ""
			(at 0 0 90)
			(layer "F.Fab")
			(effects
				(font
					(size 1.27 1.27)
				)
			)
		)
		(duplicate_pad_numbers_are_jumpers no)
		(fp_poly
			(pts
				(xy -0.2794 -0.1016) (xy 0.2794 -0.1016) (xy 0.2794 0.9906) (xy -0.2794 0.9906)
			)
			(stroke
				(width 0)
				(type default)
			)
			(fill no)
			(layer "F.CrtYd")
		)
		(fp_line
			(start 0.2794 -0.1016)
			(end -0.2794 -0.1016)
			(stroke
				(width 0.1)
				(type default)
			)
			(layer "F.Fab")
		)
		(fp_line
			(start -0.2794 -0.1016)
			(end -0.2794 0.9906)
			(stroke
				(width 0.1)
				(type default)
			)
			(layer "F.Fab")
		)
		(fp_line
			(start 0.2794 0.9906)
			(end 0.2794 -0.1016)
			(stroke
				(width 0.1)
				(type default)
			)
			(layer "F.Fab")
		)
		(fp_line
			(start -0.2794 0.9906)
			(end 0.2794 0.9906)
			(stroke
				(width 0.1)
				(type default)
			)
			(layer "F.Fab")
		)
		(pad "1" smd rect
			(at 0 0 90)
			(size 0.508 0.508)
			(layers "F.Cu" "F.Mask" "F.Paste")
			(net "P3V3_STBY")
		)
		(pad "2" smd rect
			(at 0 0.889 90)
			(size 0.508 0.508)
			(layers "F.Cu" "F.Mask" "F.Paste")
			(net "IRQ_PVCCIO_CPU1_VRHOT_N")
		)
		(zone
			(layer "F.Cu")
			(hatch none 0.5)
			(connect_pads
				(clearance 0)
			)
			(min_thickness 0.25)
			(keepout
				(tracks allowed)
				(vias not_allowed)
				(pads allowed)
				(copperpour not_allowed)
				(footprints allowed)
			)
			(placement
				(enabled no)
				(sheetname "")
			)
			(fill
				(thermal_gap 0.5)
				(thermal_bridge_width 0.5)
				(island_removal_mode 0)
			)
			(polygon
				(pts
					(xy 164.338 -69.6722) (xy 164.338 -70.1802) (xy 164.719 -70.1802) (xy 164.719 -69.6722)
				)
			)
		)
		(zone
			(layer "F.Cu")
			(hatch none 0.5)
			(connect_pads
				(clearance 0)
			)
			(min_thickness 0.25)
			(keepout
				(tracks not_allowed)
				(vias allowed)
				(pads allowed)
				(copperpour not_allowed)
				(footprints allowed)
			)
			(placement
				(enabled no)
				(sheetname "")
			)
			(fill
				(thermal_gap 0.5)
				(thermal_bridge_width 0.5)
				(island_removal_mode 0)
			)
			(polygon
				(pts
					(xy 164.719 -69.6722) (xy 164.719 -70.1802) (xy 164.338 -70.1802) (xy 164.338 -69.6722)
				)
			)
		)
	)
	(footprint ""
		(layer "F.Cu")
		(at 20.7518 -88.138 90)
		(property "Reference" "C1D1"
			(at 0 0 90)
			(layer "F.SilkS")
			(hide yes)
			(effects
				(font
					(size 1.27 1.27)
				)
			)
		)
		(property "Value" ""
			(at 0 0 90)
			(layer "F.Fab")
			(effects
				(font
					(size 1.27 1.27)
				)
			)
		)
		(duplicate_pad_numbers_are_jumpers no)
		(fp_rect
			(start -0.3048 -0.1016)
			(end 0.3048 0.9906)
			(stroke
				(width 0)
				(type default)
			)
			(fill no)
			(layer "F.CrtYd")
		)
		(fp_line
			(start 0.3048 -0.1016)
			(end -0.3048 -0.1016)
			(stroke
				(width 0.1)
				(type default)
			)
			(layer "F.Fab")
		)
		(fp_line
			(start -0.3048 -0.1016)
			(end -0.3048 0.9906)
			(stroke
				(width 0.1)
				(type default)
			)
			(layer "F.Fab")
		)
		(fp_line
			(start 0.3048 0.9906)
			(end 0.3048 -0.1016)
			(stroke
				(width 0.1)
				(type default)
			)
			(layer "F.Fab")
		)
		(fp_line
			(start -0.3048 0.9906)
			(end 0.3048 0.9906)
			(stroke
				(width 0.1)
				(type default)
			)
			(layer "F.Fab")
		)
		(pad "1" smd rect
			(at 0 0 90)
			(size 0.508 0.508)
			(layers "F.Cu" "F.Mask" "F.Paste")
			(net "VSENSE_PVCCIN_CPU1_AVSP")
		)
		(pad "2" smd rect
			(at 0 0.889 90)
			(size 0.508 0.508)
			(layers "F.Cu" "F.Mask" "F.Paste")
			(net "VSENSE_PVCCIN_CPU1_N")
		)
		(zone
			(layer "F.Cu")
			(hatch none 0.5)
			(connect_pads
				(clearance 0)
			)
			(min_thickness 0.25)
			(keepout
				(tracks allowed)
				(vias not_allowed)
				(pads allowed)
				(copperpour not_allowed)
				(footprints allowed)
			)
			(placement
				(enabled no)
				(sheetname "")
			)
			(fill
				(thermal_gap 0.5)
				(thermal_bridge_width 0.5)
				(island_removal_mode 0)
			)
			(polygon
				(pts
					(xy 21.0058 -87.884) (xy 21.3868 -87.884) (xy 21.3868 -88.392) (xy 21.0058 -88.392)
				)
			)
		)
		(zone
			(layer "F.Cu")
			(hatch none 0.5)
			(connect_pads
				(clearance 0)
			)
			(min_thickness 0.25)
			(keepout
				(tracks not_allowed)
				(vias allowed)
				(pads allowed)
				(copperpour not_allowed)
				(footprints allowed)
			)
			(placement
				(enabled no)
				(sheetname "")
			)
			(fill
				(thermal_gap 0.5)
				(thermal_bridge_width 0.5)
				(island_removal_mode 0)
			)
			(polygon
				(pts
					(xy 21.0058 -87.884) (xy 21.3868 -87.884) (xy 21.3868 -88.392) (xy 21.0058 -88.392)
				)
			)
		)
	)
	(footprint ""
		(layer "F.Cu")
		(at 24.7904 -42.6212 -90)
		(property "Reference" "CR1E1"
			(at 1.24587 0.2794 0)
			(unlocked yes)
			(layer "F.SilkS")
			(effects
				(font
					(size 0.7874 0.5842)
					(thickness 0.1524)
				)
				(justify left)
			)
		)
		(property "Value" ""
			(at 0 0 270)
			(layer "F.Fab")
			(effects
				(font
					(size 1.27 1.27)
				)
			)
		)
		(duplicate_pad_numbers_are_jumpers no)
		(fp_line
			(start -0.980186 2.623312)
			(end -0.980186 1.711706)
			(stroke
				(width 0.1524)
				(type default)
			)
			(layer "F.SilkS")
		)
		(fp_line
			(start -1.461008 1.711706)
			(end -0.980186 0.87884)
			(stroke
				(width 0.1524)
				(type default)
			)
			(layer "F.SilkS")
		)
		(fp_line
			(start -0.980186 1.711706)
			(end -1.461008 1.711706)
			(stroke
				(width 0.1524)
				(type default)
			)
			(layer "F.SilkS")
		)
		(fp_line
			(start -0.499364 1.711706)
			(end -0.980186 1.711706)
			(stroke
				(width 0.1524)
				(type default)
			)
			(layer "F.SilkS")
		)
		(fp_line
			(start -0.980186 0.87884)
			(end -0.499364 1.711706)
			(stroke
				(width 0.1524)
				(type default)
			)
			(layer "F.SilkS")
		)
		(fp_line
			(start -0.499364 0.87884)
			(end -1.461008 0.87884)
			(stroke
				(width 0.1524)
				(type default)
			)
			(layer "F.SilkS")
		)
		(fp_line
			(start -0.980186 -0.244602)
			(end -0.980186 0.87884)
			(stroke
				(width 0.1524)
				(type default)
			)
			(layer "F.SilkS")
		)
		(fp_rect
			(start 0.67437 2.04216)
			(end -0.67437 0.24384)
			(stroke
				(width 0)
				(type default)
			)
			(fill no)
			(layer "F.CrtYd")
		)
		(fp_line
			(start -0.67437 2.04216)
			(end 0.67437 2.04216)
			(stroke
				(width 0.1)
				(type default)
			)
			(layer "F.Fab")
		)
		(fp_line
			(start 0.67437 2.04216)
			(end 0.67437 0.24384)
			(stroke
				(width 0.1)
				(type default)
			)
			(layer "F.Fab")
		)
		(fp_line
			(start -1.461008 1.711706)
			(end -0.980186 0.87884)
			(stroke
				(width 0.1)
				(type default)
			)
			(layer "F.Fab")
		)
		(fp_line
			(start -0.980186 1.711706)
			(end -0.980186 2.623312)
			(stroke
				(width 0.1)
				(type default)
			)
			(layer "F.Fab")
		)
		(fp_line
			(start -0.499364 1.711706)
			(end -1.461008 1.711706)
			(stroke
				(width 0.1)
				(type default)
			)
			(layer "F.Fab")
		)
		(fp_line
			(start -0.980186 0.87884)
			(end -0.499364 1.711706)
			(stroke
				(width 0.1)
				(type default)
			)
			(layer "F.Fab")
		)
		(fp_line
			(start -0.980186 0.87884)
			(end -0.980186 -0.244602)
			(stroke
				(width 0.1)
				(type default)
			)
			(layer "F.Fab")
		)
		(fp_line
			(start -0.499364 0.87884)
			(end -1.461008 0.87884)
			(stroke
				(width 0.1)
				(type default)
			)
			(layer "F.Fab")
		)
		(fp_line
			(start -0.67437 0.24384)
			(end -0.67437 2.04216)
			(stroke
				(width 0.1)
				(type default)
			)
			(layer "F.Fab")
		)
		(fp_line
			(start 0.67437 0.24384)
			(end -0.67437 0.24384)
			(stroke
				(width 0.1)
				(type default)
			)
			(layer "F.Fab")
		)
		(pad "1" smd rect
			(at 0 0 270)
			(size 0.4064 1.016)
			(layers "F.Cu" "F.Mask" "F.Paste")
			(net "P5V_STBY")
		)
		(pad "2" smd rect
			(at 0 2.286 270)
			(size 0.4064 1.016)
			(layers "F.Cu" "F.Mask" "F.Paste")
			(net "FAN_PWM_OUT_SYS0_R")
		)
	)
	(footprint ""
		(layer "F.Cu")
		(at 29.635958 -61.716158 90)
		(property "Reference" "CT25"
			(at -0.78613 0.7874 180)
			(unlocked yes)
			(layer "F.SilkS")
			(effects
				(font
					(size 0.7874 0.5842)
					(thickness 0.1524)
				)
				(justify left)
			)
		)
		(property "Value" ""
			(at 0 0 90)
			(layer "F.Fab")
			(effects
				(font
					(size 1.27 1.27)
				)
			)
		)
		(duplicate_pad_numbers_are_jumpers no)
		(fp_poly
			(pts
				(xy 0.3048 -0.1016) (xy 0.3048 0.9906) (xy -0.3048 0.9906) (xy -0.3048 -0.1016)
			)
			(stroke
				(width 0)
				(type default)
			)
			(fill no)
			(layer "F.CrtYd")
		)
		(fp_line
			(start 0.3048 -0.1016)
			(end -0.3048 -0.1016)
			(stroke
				(width 0.1)
				(type default)
			)
			(layer "F.Fab")
		)
		(fp_line
			(start -0.3048 -0.1016)
			(end -0.3048 0.9906)
			(stroke
				(width 0.1)
				(type default)
			)
			(layer "F.Fab")
		)
		(fp_line
			(start 0.3048 0.9906)
			(end 0.3048 -0.1016)
			(stroke
				(width 0.1)
				(type default)
			)
			(layer "F.Fab")
		)
		(fp_line
			(start -0.3048 0.9906)
			(end 0.3048 0.9906)
			(stroke
				(width 0.1)
				(type default)
			)
			(layer "F.Fab")
		)
		(pad "1" smd rect
			(at 0 0 90)
			(size 0.508 0.508)
			(layers "F.Cu" "F.Mask" "F.Paste")
			(net "VR_PVCCIN_CPU1_AIREF2")
		)
		(pad "2" smd rect
			(at 0 0.889 90)
			(size 0.508 0.508)
			(layers "F.Cu" "F.Mask" "F.Paste")
			(net "GND")
		)
		(zone
			(layer "F.Cu")
			(hatch none 0.5)
			(connect_pads
				(clearance 0)
			)
			(min_thickness 0.25)
			(keepout
				(tracks allowed)
				(vias not_allowed)
				(pads allowed)
				(copperpour not_allowed)
				(footprints allowed)
			)
			(placement
				(enabled no)
				(sheetname "")
			)
			(fill
				(thermal_gap 0.5)
				(thermal_bridge_width 0.5)
				(island_removal_mode 0)
			)
			(polygon
				(pts
					(xy 29.889958 -61.462158) (xy 29.889958 -61.970158) (xy 30.270958 -61.970158) (xy 30.270958 -61.462158)
				)
			)
		)
		(zone
			(layer "F.Cu")
			(hatch none 0.5)
			(connect_pads
				(clearance 0)
			)
			(min_thickness 0.25)
			(keepout
				(tracks not_allowed)
				(vias allowed)
				(pads allowed)
				(copperpour not_allowed)
				(footprints allowed)
			)
			(placement
				(enabled no)
				(sheetname "")
			)
			(fill
				(thermal_gap 0.5)
				(thermal_bridge_width 0.5)
				(island_removal_mode 0)
			)
			(polygon
				(pts
					(xy 30.270958 -61.462158) (xy 30.270958 -61.970158) (xy 29.889958 -61.970158) (xy 29.889958 -61.462158)
				)
			)
		)
	)
	(footprint ""
		(layer "F.Cu")
		(at 381.4445 -138.9761 90)
		(property "Reference" "C7B4"
			(at 0 0 90)
			(layer "F.SilkS")
			(hide yes)
			(effects
				(font
					(size 1.27 1.27)
				)
			)
		)
		(property "Value" ""
			(at 0 0 90)
			(layer "F.Fab")
			(effects
				(font
					(size 1.27 1.27)
				)
			)
		)
		(duplicate_pad_numbers_are_jumpers no)
		(fp_rect
			(start -0.7239 -0.2159)
			(end 0.7239 1.9939)
			(stroke
				(width 0)
				(type default)
			)
			(fill no)
			(layer "F.CrtYd")
		)
		(fp_line
			(start 0.7239 -0.2159)
			(end -0.7239 -0.2159)
			(stroke
				(width 0.1)
				(type default)
			)
			(layer "F.Fab")
		)
		(fp_line
			(start -0.7239 -0.2159)
			(end -0.7239 1.9939)
			(stroke
				(width 0.1)
				(type default)
			)
			(layer "F.Fab")
		)
		(fp_line
			(start 0.7239 1.9939)
			(end 0.7239 -0.2159)
			(stroke
				(width 0.1)
				(type default)
			)
			(layer "F.Fab")
		)
		(fp_line
			(start -0.7239 1.9939)
			(end 0.7239 1.9939)
			(stroke
				(width 0.1)
				(type default)
			)
			(layer "F.Fab")
		)
		(pad "1" smd rect
			(at 0 0 90)
			(size 1.27 1.016)
			(layers "F.Cu" "F.Mask" "F.Paste")
			(net "PVNN_PCH_STBY")
		)
		(pad "2" smd rect
			(at 0 1.778 90)
			(size 1.27 1.016)
			(layers "F.Cu" "F.Mask" "F.Paste")
			(net "GND")
		)
		(zone
			(layer "F.Cu")
			(hatch none 0.5)
			(connect_pads
				(clearance 0)
			)
			(min_thickness 0.25)
			(keepout
				(tracks not_allowed)
				(vias allowed)
				(pads allowed)
				(copperpour not_allowed)
				(footprints allowed)
			)
			(placement
				(enabled no)
				(sheetname "")
			)
			(fill
				(thermal_gap 0.5)
				(thermal_bridge_width 0.5)
				(island_removal_mode 0)
			)
			(polygon
				(pts
					(xy 381.9525 -138.3411) (xy 382.7145 -138.3411) (xy 382.7145 -139.6111) (xy 381.9525 -139.6111)
				)
			)
		)
	)
)
